FILE_TYPE=LIBRARY_PARTS;
primitive 'INA183A1IDBVR';
  pin
    'GND0':
      PIN_NUMBER='(1)';
      PINUSE='POWER';
      NO_LOAD_CHECK='Both';
      NO_IO_CHECK='Both';
      NO_ASSERT_CHECK='TRUE';
      NO_DIR_CHECK='TRUE';
      ALLOW_CONNECT='TRUE';
    'GND1':
      PIN_NUMBER='(2)';
      PINUSE='POWER';
      NO_LOAD_CHECK='Both';
      NO_IO_CHECK='Both';
      NO_ASSERT_CHECK='TRUE';
      NO_DIR_CHECK='TRUE';
      ALLOW_CONNECT='TRUE';
    'OUT':
      PIN_NUMBER='(3)';
      OUTPUT_LOAD='(1.0,-1.0)';
    'IN-':
      PIN_NUMBER='(4)';
      INPUT_LOAD='(-0.01,0.01)';
    'IN+':
      PIN_NUMBER='(5)';
      INPUT_LOAD='(-0.01,0.01)';
  end_pin;
  body
    PART_NAME='INA183A1IDBVR';
    BODY_NAME='INA183A1IDBVR';
    PHYS_DES_PREFIX='U';
    CLASS='IC';
  end_body;
end_primitive;

END.
